(kicad_pcb
	(version 20241229)
	(generator "pcbnew")
	(generator_version "9.0")
	(general
		(thickness 1.711)
		(legacy_teardrops no)
	)
	(paper "A4")
	(title_block
		(title "Antmicro Baseboard for Jetson AGX Thor")
		(date "2026-02-18")
		(rev "1.1.0")
		(company "Antmicro Ltd")
		(comment 1 "www.antmicro.com")
		(comment 9 "footprints 1113-1116 of 1170")
	)
	(layers
		(0 "F.Cu" signal)
		(4 "In1.Cu" signal)
		(6 "In2.Cu" signal)
		(8 "In3.Cu" signal)
		(10 "In4.Cu" jumper)
		(12 "In5.Cu" signal)
		(14 "In6.Cu" signal)
		(16 "In7.Cu" signal)
		(18 "In8.Cu" signal)
		(2 "B.Cu" signal)
		(9 "F.Adhes" user "F.Adhesive")
		(11 "B.Adhes" user "B.Adhesive")
		(13 "F.Paste" user)
		(15 "B.Paste" user)
		(5 "F.SilkS" user "F.Silkscreen")
		(7 "B.SilkS" user "B.Silkscreen")
		(1 "F.Mask" user)
		(3 "B.Mask" user)
		(17 "Dwgs.User" user "User.Drawings")
		(19 "Cmts.User" user "User.Comments")
		(21 "Eco1.User" user "User.Eco1")
		(23 "Eco2.User" user "User.Eco2")
		(25 "Edge.Cuts" user)
		(27 "Margin" user)
		(31 "F.CrtYd" user "F.Courtyard")
		(29 "B.CrtYd" user "B.Courtyard")
		(35 "F.Fab" user)
		(33 "B.Fab" user)
	)
	(footprint "antmicro-footprints:C_0402_1005Metric"
		(layer "B.Cu")
		(at 205.3 130.5 -90)
		(descr "Capacitor SMD 0402")
		(tags "capacitor SMD 0402")
		(property "Reference" "C85"
			(at 0.9 -0.5 90)
			(layer "B.SilkS")
			(effects
				(font
					(size 0.7 0.7)
					(thickness 0.15)
				)
				(justify left bottom mirror)
			)
		)
		(property "Value" "C_100n_0402"
			(at -1.022927 -2.155213 90)
			(layer "B.Fab")
			(effects
				(font
					(size 0.7 0.7)
					(thickness 0.15)
				)
				(justify left bottom mirror)
			)
		)
		(property "Datasheet" "https://www.murata.com/products/productdetail?partno=GRM155R61H104KE14%23"
			(at 0 0 90)
			(layer "B.Fab")
			(hide yes)
			(effects
				(font
					(size 1.27 1.27)
					(thickness 0.15)
				)
				(justify mirror)
			)
		)
		(property "Description" "SMD Multilayer Ceramic Capacitor, 0.1 µF, 50 V, 0402 [1005 Metric], ± 10%, X5R, GRM Series"
			(at 0 0 90)
			(layer "B.Fab")
			(hide yes)
			(effects
				(font
					(size 1.27 1.27)
					(thickness 0.15)
				)
				(justify mirror)
			)
		)
		(property "MPN" "GRM155R61H104KE14D"
			(at 0 0 90)
			(unlocked yes)
			(layer "B.Fab")
			(hide yes)
			(effects
				(font
					(size 1 1)
					(thickness 0.15)
				)
				(justify mirror)
			)
		)
		(property "Val" "100n"
			(at 0 0 90)
			(unlocked yes)
			(layer "B.Fab")
			(hide yes)
			(effects
				(font
					(size 1 1)
					(thickness 0.15)
				)
				(justify mirror)
			)
		)
		(property "Voltage" "50V"
			(at 0 0 90)
			(unlocked yes)
			(layer "B.Fab")
			(hide yes)
			(effects
				(font
					(size 1 1)
					(thickness 0.15)
				)
				(justify mirror)
			)
		)
		(property "Dielectric" "X5R"
			(at 0 0 90)
			(unlocked yes)
			(layer "B.Fab")
			(hide yes)
			(effects
				(font
					(size 1 1)
					(thickness 0.15)
				)
				(justify mirror)
			)
		)
		(property "Manufacturer" "Murata"
			(at 0 0 90)
			(unlocked yes)
			(layer "B.Fab")
			(hide yes)
			(effects
				(font
					(size 1 1)
					(thickness 0.15)
				)
				(justify mirror)
			)
		)
		(property "License" "Apache-2.0"
			(at 0 0 90)
			(unlocked yes)
			(layer "B.Fab")
			(hide yes)
			(effects
				(font
					(size 1 1)
					(thickness 0.15)
				)
				(justify mirror)
			)
		)
		(property "Author" "Antmicro"
			(at 0 0 90)
			(unlocked yes)
			(layer "B.Fab")
			(hide yes)
			(effects
				(font
					(size 1 1)
					(thickness 0.15)
				)
				(justify mirror)
			)
		)
		(sheetname "/USB Hub/")
		(sheetfile "usb_hub.kicad_sch")
		(attr smd)
		(fp_poly
			(pts
				(xy -0.925 0.47) (xy 0.925 0.47) (xy 0.925 -0.47) (xy -0.925 -0.47)
			)
			(stroke
				(width 0.05)
				(type default)
			)
			(fill no)
			(layer "B.CrtYd")
		)
		(fp_line
			(start -0.494 0.25)
			(end 0.504 0.25)
			(stroke
				(width 0.15)
				(type solid)
			)
			(layer "B.Fab")
		)
		(fp_line
			(start 0.504 0.25)
			(end 0.504 -0.248)
			(stroke
				(width 0.15)
				(type solid)
			)
			(layer "B.Fab")
		)
		(fp_line
			(start -0.494 -0.248)
			(end -0.494 0.25)
			(stroke
				(width 0.15)
				(type solid)
			)
			(layer "B.Fab")
		)
		(fp_line
			(start 0.504 -0.248)
			(end -0.494 -0.248)
			(stroke
				(width 0.15)
				(type solid)
			)
			(layer "B.Fab")
		)
		(fp_text user "Author: Antmicro"
			(at -0.939 -3.399 90)
			(layer "B.Fab")
			(effects
				(font
					(size 0.7 0.7)
					(thickness 0.15)
				)
				(justify left bottom mirror)
			)
		)
		(fp_text user "${REFERENCE}"
			(at -0.939 -4.599 90)
			(layer "B.Fab")
			(effects
				(font
					(size 0.7 0.7)
					(thickness 0.15)
				)
				(justify left bottom mirror)
			)
		)
		(fp_text user "License: Apache-2.0"
			(at -0.939 -5.799 90)
			(layer "B.Fab")
			(effects
				(font
					(size 0.7 0.7)
					(thickness 0.15)
				)
				(justify left bottom mirror)
			)
		)
		(pad "1" smd roundrect
			(at -0.48 0 270)
			(size 0.59 0.64)
			(layers "B.Cu" "B.Mask" "B.Paste")
			(roundrect_rratio 0.25)
			(net 1 "GND")
			(pintype "passive")
		)
		(pad "2" smd roundrect
			(at 0.48 0 270)
			(size 0.59 0.64)
			(layers "B.Cu" "B.Mask" "B.Paste")
			(roundrect_rratio 0.25)
			(net 2 "+3V3")
			(pintype "passive")
		)
	)
	(footprint "antmicro-footprints:R_0402_1005Metric"
		(layer "B.Cu")
		(at 216 87.185 180)
		(descr "Resistor SMD 0402")
		(tags "resistor SMD 0402")
		(property "Reference" "R139"
			(at -7.6 -2.415 0)
			(layer "B.SilkS")
			(effects
				(font
					(size 0.7 0.7)
					(thickness 0.15)
				)
				(justify left bottom mirror)
			)
		)
		(property "Value" "R_1k_0402"
			(at -1.011843 -1.772047 0)
			(layer "B.Fab")
			(effects
				(font
					(size 0.7 0.7)
					(thickness 0.15)
				)
				(justify left bottom mirror)
			)
		)
		(property "Datasheet" "https://www.bourns.com/docs/product-datasheets/cr.pdf"
			(at 0 0 0)
			(layer "B.Fab")
			(hide yes)
			(effects
				(font
					(size 1.27 1.27)
					(thickness 0.15)
				)
				(justify mirror)
			)
		)
		(property "Description" "SMD Chip Resistor, 1 kohm, ± 1%, 63 mW, 0402 [1005 Metric], Thick Film, General Purpose"
			(at 0 0 0)
			(layer "B.Fab")
			(hide yes)
			(effects
				(font
					(size 1.27 1.27)
					(thickness 0.15)
				)
				(justify mirror)
			)
		)
		(property "Manufacturer" "Bourns"
			(at 0 0 0)
			(unlocked yes)
			(layer "B.Fab")
			(hide yes)
			(effects
				(font
					(size 1 1)
					(thickness 0.15)
				)
				(justify mirror)
			)
		)
		(property "MPN" "CR0402-FX-1001GLF"
			(at 0 0 0)
			(unlocked yes)
			(layer "B.Fab")
			(hide yes)
			(effects
				(font
					(size 1 1)
					(thickness 0.15)
				)
				(justify mirror)
			)
		)
		(property "Val" "1k"
			(at 0 0 0)
			(unlocked yes)
			(layer "B.Fab")
			(hide yes)
			(effects
				(font
					(size 1 1)
					(thickness 0.15)
				)
				(justify mirror)
			)
		)
		(property "License" "Apache-2.0"
			(at 0 0 0)
			(unlocked yes)
			(layer "B.Fab")
			(hide yes)
			(effects
				(font
					(size 1 1)
					(thickness 0.15)
				)
				(justify mirror)
			)
		)
		(property "Author" "Antmicro"
			(at 0 0 0)
			(unlocked yes)
			(layer "B.Fab")
			(hide yes)
			(effects
				(font
					(size 1 1)
					(thickness 0.15)
				)
				(justify mirror)
			)
		)
		(property "Tolerance" "1%"
			(at 0 0 0)
			(unlocked yes)
			(layer "B.Fab")
			(hide yes)
			(effects
				(font
					(size 1 1)
					(thickness 0.15)
				)
				(justify mirror)
			)
		)
		(sheetname "/USB DP Alt mode/")
		(sheetfile "usb_dp.kicad_sch")
		(attr smd exclude_from_pos_files exclude_from_bom dnp)
		(fp_rect
			(start -0.925 0.47)
			(end 0.925 -0.47)
			(stroke
				(width 0.05)
				(type default)
			)
			(fill no)
			(layer "B.CrtYd")
		)
		(fp_rect
			(start -0.5 0.25)
			(end 0.5 -0.25)
			(stroke
				(width 0.15)
				(type solid)
			)
			(fill no)
			(layer "B.Fab")
		)
		(fp_text user "${REFERENCE}"
			(at -0.95 -3.168 0)
			(layer "B.Fab")
			(effects
				(font
					(size 0.7 0.7)
					(thickness 0.15)
				)
				(justify left bottom mirror)
			)
		)
		(fp_text user "License: Apache-2.0"
			(at -0.95 -5.169 0)
			(layer "B.Fab")
			(effects
				(font
					(size 0.7 0.7)
					(thickness 0.15)
				)
				(justify left bottom mirror)
			)
		)
		(fp_text user "Author: Antmicro"
			(at -0.95 -4.169 0)
			(layer "B.Fab")
			(effects
				(font
					(size 0.7 0.7)
					(thickness 0.15)
				)
				(justify left bottom mirror)
			)
		)
		(pad "1" smd roundrect
			(at -0.48 0 180)
			(size 0.59 0.64)
			(layers "B.Cu" "B.Mask" "B.Paste")
			(roundrect_rratio 0.25)
			(net 968 "/USB DP Alt mode/USBC1_EQ0")
			(pintype "passive")
		)
		(pad "2" smd roundrect
			(at 0.48 0 180)
			(size 0.59 0.64)
			(layers "B.Cu" "B.Mask" "B.Paste")
			(roundrect_rratio 0.25)
			(net 1 "GND")
			(pintype "passive")
		)
	)
	(footprint "antmicro-footprints:R_0402_1005Metric"
		(layer "B.Cu")
		(at 235.8 95.6 180)
		(descr "Resistor SMD 0402")
		(tags "resistor SMD 0402")
		(property "Reference" "R146"
			(at -3.845 -1.254999 0)
			(layer "B.SilkS")
			(effects
				(font
					(size 0.7 0.7)
					(thickness 0.15)
				)
				(justify left bottom mirror)
			)
		)
		(property "Value" "R_2k2_0402"
			(at -1.011843 -1.772046 0)
			(layer "B.Fab")
			(effects
				(font
					(size 0.7 0.7)
					(thickness 0.15)
				)
				(justify left bottom mirror)
			)
		)
		(property "Datasheet" "https://www.bourns.com/docs/product-datasheets/cr.pdf"
			(at 0 0 0)
			(layer "B.Fab")
			(hide yes)
			(effects
				(font
					(size 1.27 1.27)
					(thickness 0.15)
				)
				(justify mirror)
			)
		)
		(property "Description" "SMD Chip Resistor, 2.2 kohm, ± 1%, 62.5 mW, 0402 [1005 Metric], Thick Film, General Purpose"
			(at 0 0 0)
			(layer "B.Fab")
			(hide yes)
			(effects
				(font
					(size 1.27 1.27)
					(thickness 0.15)
				)
				(justify mirror)
			)
		)
		(property "Manufacturer" "Bourns"
			(at 0 0 0)
			(unlocked yes)
			(layer "B.Fab")
			(hide yes)
			(effects
				(font
					(size 1 1)
					(thickness 0.15)
				)
				(justify mirror)
			)
		)
		(property "MPN" "CR0402-FX-2201GLF"
			(at 0 0 0)
			(unlocked yes)
			(layer "B.Fab")
			(hide yes)
			(effects
				(font
					(size 1 1)
					(thickness 0.15)
				)
				(justify mirror)
			)
		)
		(property "Val" "2k2"
			(at 0 0 0)
			(unlocked yes)
			(layer "B.Fab")
			(hide yes)
			(effects
				(font
					(size 1 1)
					(thickness 0.15)
				)
				(justify mirror)
			)
		)
		(property "License" "Apache-2.0"
			(at 0 0 0)
			(unlocked yes)
			(layer "B.Fab")
			(hide yes)
			(effects
				(font
					(size 1 1)
					(thickness 0.15)
				)
				(justify mirror)
			)
		)
		(property "Author" "Antmicro"
			(at 0 0 0)
			(unlocked yes)
			(layer "B.Fab")
			(hide yes)
			(effects
				(font
					(size 1 1)
					(thickness 0.15)
				)
				(justify mirror)
			)
		)
		(property "Tolerance" "1%"
			(at 0 0 0)
			(unlocked yes)
			(layer "B.Fab")
			(hide yes)
			(effects
				(font
					(size 1 1)
					(thickness 0.15)
				)
				(justify mirror)
			)
		)
		(sheetname "/USB DP Alt mode/")
		(sheetfile "usb_dp.kicad_sch")
		(attr smd)
		(fp_poly
			(pts
				(xy -0.925 0.47) (xy -0.925 -0.47) (xy 0.925 -0.47) (xy 0.925 0.47)
			)
			(stroke
				(width 0.05)
				(type default)
			)
			(fill no)
			(layer "B.CrtYd")
		)
		(fp_poly
			(pts
				(xy -0.5 0.25) (xy -0.5 -0.25) (xy 0.5 -0.25) (xy 0.5 0.25)
			)
			(stroke
				(width 0.15)
				(type solid)
			)
			(fill no)
			(layer "B.Fab")
		)
		(fp_text user "${REFERENCE}"
			(at -0.95 -3.168 0)
			(layer "B.Fab")
			(effects
				(font
					(size 0.7 0.7)
					(thickness 0.15)
				)
				(justify left bottom mirror)
			)
		)
		(fp_text user "License: Apache-2.0"
			(at -0.949999 -5.169 0)
			(layer "B.Fab")
			(effects
				(font
					(size 0.7 0.7)
					(thickness 0.15)
				)
				(justify left bottom mirror)
			)
		)
		(fp_text user "Author: Antmicro"
			(at -0.95 -4.169 0)
			(layer "B.Fab")
			(effects
				(font
					(size 0.7 0.7)
					(thickness 0.15)
				)
				(justify left bottom mirror)
			)
		)
		(pad "1" smd roundrect
			(at -0.48 0 180)
			(size 0.59 0.64)
			(layers "B.Cu" "B.Mask" "B.Paste")
			(roundrect_rratio 0.25)
			(net 1 "GND")
			(pintype "passive")
		)
		(pad "2" smd roundrect
			(at 0.48 0 180)
			(size 0.59 0.64)
			(layers "B.Cu" "B.Mask" "B.Paste")
			(roundrect_rratio 0.25)
			(net 972 "Net-(U35-ISET)")
			(pintype "passive")
		)
	)
	(footprint "antmicro-footprints:TP_SMD_0.75mm"
		(layer "B.Cu")
		(at 134.8 72.6 -90)
		(property "Reference" "TP107"
			(at 0.4 -3.9 0)
			(layer "B.SilkS")
			(effects
				(font
					(size 0.7 0.7)
					(thickness 0.15)
				)
				(justify left bottom mirror)
			)
		)
		(property "Value" "TP_0.75mm_SMD"
			(at 0 -1.2 90)
			(layer "B.Fab")
			(effects
				(font
					(size 0.7 0.7)
					(thickness 0.15)
				)
				(justify left bottom mirror)
			)
		)
		(property "Description" "SMT test point"
			(at 0 0 90)
			(layer "B.Fab")
			(hide yes)
			(effects
				(font
					(size 1.27 1.27)
					(thickness 0.15)
				)
				(justify mirror)
			)
		)
		(property "MPN" ""
			(at 0 0 90)
			(unlocked yes)
			(layer "B.Fab")
			(hide yes)
			(effects
				(font
					(size 1 1)
					(thickness 0.15)
				)
				(justify mirror)
			)
		)
		(property "Manufacturer" ""
			(at 0 0 90)
			(unlocked yes)
			(layer "B.Fab")
			(hide yes)
			(effects
				(font
					(size 1 1)
					(thickness 0.15)
				)
				(justify mirror)
			)
		)
		(property "Author" "Antmicro"
			(at 0 0 90)
			(unlocked yes)
			(layer "B.Fab")
			(hide yes)
			(effects
				(font
					(size 1 1)
					(thickness 0.15)
				)
				(justify mirror)
			)
		)
		(property "License" "Apache-2.0"
			(at 0 0 90)
			(unlocked yes)
			(layer "B.Fab")
			(hide yes)
			(effects
				(font
					(size 1 1)
					(thickness 0.15)
				)
				(justify mirror)
			)
		)
		(sheetname "/SoM_IO/")
		(sheetfile "som_io.kicad_sch")
		(attr exclude_from_pos_files exclude_from_bom)
		(fp_circle
			(center 0 0)
			(end 0.475 0)
			(stroke
				(width 0.05)
				(type default)
			)
			(fill no)
			(layer "B.CrtYd")
		)
		(fp_text user "Author: Antmicro"
			(at -0.4 -3.901 90)
			(layer "B.Fab")
			(effects
				(font
					(size 0.7 0.7)
					(thickness 0.15)
				)
				(justify left bottom mirror)
			)
		)
		(fp_text user "License: Apache-2.0"
			(at -0.4 -5.101 90)
			(layer "B.Fab")
			(effects
				(font
					(size 0.7 0.7)
					(thickness 0.15)
				)
				(justify left bottom mirror)
			)
		)
		(fp_text user "${REFERENCE}"
			(at -0.4 -2.7 90)
			(layer "B.Fab")
			(effects
				(font
					(size 0.7 0.7)
					(thickness 0.15)
				)
				(justify left bottom mirror)
			)
		)
		(pad "1" smd circle
			(at 0 0 270)
			(size 0.75 0.75)
			(layers "B.Cu" "B.Mask")
			(net 138 "/SoM_IO/UART1.TX")
			(pinfunction "1")
			(pintype "passive")
		)
	)
)
